(kicad_pcb
	(version 20260206)
	(generator "pcbnew")
	(generator_version "10.0")
	(general
		(thickness 1.6)
		(legacy_teardrops no)
	)
	(paper "A4")
	(title_block
		(title "01162023_DA0F0TEBIF0_F0T_Expander_BD_F_brd_V02_OCP.brd")
		(comment 1 "Grand Teton / footprints 567-574 of 9728")
	)
	(layers
		(0 "F.Cu" signal "TOP")
		(4 "In1.Cu" signal "GND")
		(6 "In2.Cu" signal "VCC")
		(8 "In3.Cu" signal "VCC1")
		(10 "In4.Cu" signal "GND1")
		(12 "In5.Cu" signal "IN1")
		(14 "In6.Cu" signal "GND2")
		(16 "In7.Cu" signal "IN2")
		(18 "In8.Cu" signal "GND3")
		(20 "In9.Cu" signal "IN3")
		(22 "In10.Cu" signal "GND4")
		(24 "In11.Cu" signal "IN4")
		(26 "In12.Cu" signal "GND5")
		(28 "In13.Cu" signal "IN5")
		(30 "In14.Cu" signal "GND6")
		(32 "In15.Cu" signal "IN6")
		(34 "In16.Cu" signal "GND7")
		(2 "B.Cu" signal "BOTTOM")
		(9 "F.Adhes" user "F.Adhesive")
		(11 "B.Adhes" user "B.Adhesive")
		(13 "F.Paste" user "Package Geometry/Pastemask Top")
		(15 "B.Paste" user "Package Geometry/Pastemask Bottom")
		(5 "F.SilkS" user "Ref Des/Silkscreen Top")
		(7 "B.SilkS" user "Ref Des/Silkscreen Bottom")
		(1 "F.Mask" user "Board Geometry/Soldermask Top")
		(3 "B.Mask" user "Board Geometry/Soldermask Bottom")
		(17 "Dwgs.User" user "User.Drawings")
		(19 "Cmts.User" user "User.Comments")
		(21 "Eco1.User" user "User.Eco1")
		(23 "Eco2.User" user "User.Eco2")
		(25 "Edge.Cuts" user "Board Geometry/Outline")
		(27 "Margin" user)
		(31 "F.CrtYd" user "Package Geometry/Place Bound Top")
		(29 "B.CrtYd" user "Package Geometry/Place Bound Bottom")
		(35 "F.Fab" user "Ref Des/Assembly Top")
		(33 "B.Fab" user "Ref Des/Assembly Bottom")
	)
	(footprint ""
		(layer "F.Cu")
		(at 386.90804 -162.044126 180)
		(property "Reference" "R328"
			(at 0 0 180)
			(layer "F.SilkS")
			(hide yes)
			(effects
				(font
					(size 1.27 1.27)
				)
			)
		)
		(property "Value" ""
			(at 0 0 180)
			(layer "F.Fab")
			(effects
				(font
					(size 1.27 1.27)
				)
			)
		)
		(duplicate_pad_numbers_are_jumpers no)
		(fp_line
			(start 0.7874 0.4064)
			(end -0.7874 0.4064)
			(stroke
				(width 0.1524)
				(type default)
			)
			(layer "F.SilkS")
		)
		(fp_line
			(start 0.7874 -0.4064)
			(end 0.7874 0.4064)
			(stroke
				(width 0.1524)
				(type default)
			)
			(layer "F.SilkS")
		)
		(fp_line
			(start -0.7874 0.4064)
			(end -0.7874 -0.4064)
			(stroke
				(width 0.1524)
				(type default)
			)
			(layer "F.SilkS")
		)
		(fp_line
			(start -0.7874 -0.4064)
			(end 0.7874 -0.4064)
			(stroke
				(width 0.1524)
				(type default)
			)
			(layer "F.SilkS")
		)
		(fp_line
			(start 0.67945 0.3048)
			(end 0.120396 0.3048)
			(stroke
				(width 0.1)
				(type default)
			)
			(layer "F.Fab")
		)
		(fp_line
			(start 0.67945 -0.3048)
			(end 0.67945 0.3048)
			(stroke
				(width 0.1)
				(type default)
			)
			(layer "F.Fab")
		)
		(fp_line
			(start 0.12065 -0.2794)
			(end 0.12065 -0.3048)
			(stroke
				(width 0.1)
				(type default)
			)
			(layer "F.Fab")
		)
		(fp_line
			(start 0.12065 -0.3048)
			(end 0.67945 -0.3048)
			(stroke
				(width 0.1)
				(type default)
			)
			(layer "F.Fab")
		)
		(fp_line
			(start 0.120396 0.3048)
			(end 0.120396 0.2794)
			(stroke
				(width 0.1)
				(type default)
			)
			(layer "F.Fab")
		)
		(fp_line
			(start 0.120396 0.2794)
			(end -0.12065 0.2794)
			(stroke
				(width 0.1)
				(type default)
			)
			(layer "F.Fab")
		)
		(fp_line
			(start -0.12065 0.3048)
			(end -0.67945 0.3048)
			(stroke
				(width 0.1)
				(type default)
			)
			(layer "F.Fab")
		)
		(fp_line
			(start -0.12065 0.2794)
			(end -0.12065 0.3048)
			(stroke
				(width 0.1)
				(type default)
			)
			(layer "F.Fab")
		)
		(fp_line
			(start -0.12065 -0.2794)
			(end 0.12065 -0.2794)
			(stroke
				(width 0.1)
				(type default)
			)
			(layer "F.Fab")
		)
		(fp_line
			(start -0.12065 -0.305054)
			(end -0.12065 -0.2794)
			(stroke
				(width 0.1)
				(type default)
			)
			(layer "F.Fab")
		)
		(fp_line
			(start -0.67945 0.3048)
			(end -0.67945 -0.305054)
			(stroke
				(width 0.1)
				(type default)
			)
			(layer "F.Fab")
		)
		(fp_line
			(start -0.67945 -0.305054)
			(end -0.12065 -0.305054)
			(stroke
				(width 0.1)
				(type default)
			)
			(layer "F.Fab")
		)
		(pad "1" smd circle
			(at -0.40005 0 180)
			(size 0 0)
			(layers "F.Cu" "F.Mask" "F.Paste")
			(net "PWRGD_NIC6_PWR_GOOD")
		)
		(pad "2" smd circle
			(at 0.40005 0 180)
			(size 0 0)
			(layers "F.Cu" "F.Mask" "F.Paste")
			(net "GND")
		)
	)
	(footprint ""
		(layer "F.Cu")
		(at 249.94743 -92.096336 90)
		(property "Reference" "C2652"
			(at 0 0 90)
			(layer "F.SilkS")
			(hide yes)
			(effects
				(font
					(size 1.27 1.27)
				)
			)
		)
		(property "Value" ""
			(at 0 0 90)
			(layer "F.Fab")
			(effects
				(font
					(size 1.27 1.27)
				)
			)
		)
		(duplicate_pad_numbers_are_jumpers no)
		(fp_line
			(start 0.7874 -0.4064)
			(end 0.7874 0.4064)
			(stroke
				(width 0.1524)
				(type default)
			)
			(layer "F.SilkS")
		)
		(fp_line
			(start -0.7874 -0.4064)
			(end 0.7874 -0.4064)
			(stroke
				(width 0.1524)
				(type default)
			)
			(layer "F.SilkS")
		)
		(fp_line
			(start 0.7874 0.4064)
			(end -0.7874 0.4064)
			(stroke
				(width 0.1524)
				(type default)
			)
			(layer "F.SilkS")
		)
		(fp_line
			(start -0.7874 0.4064)
			(end -0.7874 -0.4064)
			(stroke
				(width 0.1524)
				(type default)
			)
			(layer "F.SilkS")
		)
		(fp_line
			(start -0.12065 -0.305054)
			(end -0.12065 -0.2794)
			(stroke
				(width 0.1)
				(type default)
			)
			(layer "F.Fab")
		)
		(fp_line
			(start -0.67945 -0.305054)
			(end -0.12065 -0.305054)
			(stroke
				(width 0.1)
				(type default)
			)
			(layer "F.Fab")
		)
		(fp_line
			(start 0.67945 -0.3048)
			(end 0.67945 0.3048)
			(stroke
				(width 0.1)
				(type default)
			)
			(layer "F.Fab")
		)
		(fp_line
			(start 0.12065 -0.3048)
			(end 0.67945 -0.3048)
			(stroke
				(width 0.1)
				(type default)
			)
			(layer "F.Fab")
		)
		(fp_line
			(start 0.12065 -0.2794)
			(end 0.12065 -0.3048)
			(stroke
				(width 0.1)
				(type default)
			)
			(layer "F.Fab")
		)
		(fp_line
			(start -0.12065 -0.2794)
			(end 0.12065 -0.2794)
			(stroke
				(width 0.1)
				(type default)
			)
			(layer "F.Fab")
		)
		(fp_line
			(start 0.120396 0.2794)
			(end -0.12065 0.2794)
			(stroke
				(width 0.1)
				(type default)
			)
			(layer "F.Fab")
		)
		(fp_line
			(start -0.12065 0.2794)
			(end -0.12065 0.3048)
			(stroke
				(width 0.1)
				(type default)
			)
			(layer "F.Fab")
		)
		(fp_line
			(start 0.67945 0.3048)
			(end 0.120396 0.3048)
			(stroke
				(width 0.1)
				(type default)
			)
			(layer "F.Fab")
		)
		(fp_line
			(start 0.120396 0.3048)
			(end 0.120396 0.2794)
			(stroke
				(width 0.1)
				(type default)
			)
			(layer "F.Fab")
		)
		(fp_line
			(start -0.12065 0.3048)
			(end -0.67945 0.3048)
			(stroke
				(width 0.1)
				(type default)
			)
			(layer "F.Fab")
		)
		(fp_line
			(start -0.67945 0.3048)
			(end -0.67945 -0.305054)
			(stroke
				(width 0.1)
				(type default)
			)
			(layer "F.Fab")
		)
		(pad "1" smd circle
			(at -0.40005 0 90)
			(size 0 0)
			(layers "F.Cu" "F.Mask" "F.Paste")
			(net "FM_CK440Q_DEV_25M_EN")
		)
		(pad "2" smd circle
			(at 0.40005 0 90)
			(size 0 0)
			(layers "F.Cu" "F.Mask" "F.Paste")
			(net "GND")
		)
	)
	(footprint ""
		(layer "F.Cu")
		(at 73.782682 -356.244906 90)
		(property "Reference" "C141"
			(at 0 0 90)
			(layer "F.SilkS")
			(hide yes)
			(effects
				(font
					(size 1.27 1.27)
				)
			)
		)
		(property "Value" ""
			(at 0 0 90)
			(layer "F.Fab")
			(effects
				(font
					(size 1.27 1.27)
				)
			)
		)
		(duplicate_pad_numbers_are_jumpers no)
		(fp_line
			(start 0.299974 -0.150114)
			(end 0.299974 0.150114)
			(stroke
				(width 0.1)
				(type default)
			)
			(layer "F.Fab")
		)
		(fp_line
			(start -0.299974 -0.150114)
			(end 0.299974 -0.150114)
			(stroke
				(width 0.1)
				(type default)
			)
			(layer "F.Fab")
		)
		(fp_line
			(start 0.299974 0.150114)
			(end -0.299974 0.150114)
			(stroke
				(width 0.1)
				(type default)
			)
			(layer "F.Fab")
		)
		(fp_line
			(start -0.299974 0.150114)
			(end -0.299974 -0.150114)
			(stroke
				(width 0.1)
				(type default)
			)
			(layer "F.Fab")
		)
		(pad "1" smd rect
			(at -0.2667 0 90)
			(size 0.3048 0.381)
			(layers "F.Cu" "F.Mask" "F.Paste")
			(net "P5E_PEX0_STN6_TX_DP<105>")
		)
		(pad "2" smd rect
			(at 0.2667 0 90)
			(size 0.3048 0.381)
			(layers "F.Cu" "F.Mask" "F.Paste")
			(net "P5E_PEX0_STN6_TX_C_DP<105>")
		)
	)
	(footprint ""
		(layer "F.Cu")
		(at 92.436442 -356.244906 90)
		(property "Reference" "C159"
			(at 0 0 90)
			(layer "F.SilkS")
			(hide yes)
			(effects
				(font
					(size 1.27 1.27)
				)
			)
		)
		(property "Value" ""
			(at 0 0 90)
			(layer "F.Fab")
			(effects
				(font
					(size 1.27 1.27)
				)
			)
		)
		(duplicate_pad_numbers_are_jumpers no)
		(fp_line
			(start 0.299974 -0.150114)
			(end 0.299974 0.150114)
			(stroke
				(width 0.1)
				(type default)
			)
			(layer "F.Fab")
		)
		(fp_line
			(start -0.299974 -0.150114)
			(end 0.299974 -0.150114)
			(stroke
				(width 0.1)
				(type default)
			)
			(layer "F.Fab")
		)
		(fp_line
			(start 0.299974 0.150114)
			(end -0.299974 0.150114)
			(stroke
				(width 0.1)
				(type default)
			)
			(layer "F.Fab")
		)
		(fp_line
			(start -0.299974 0.150114)
			(end -0.299974 -0.150114)
			(stroke
				(width 0.1)
				(type default)
			)
			(layer "F.Fab")
		)
		(pad "1" smd rect
			(at -0.2667 0 90)
			(size 0.3048 0.381)
			(layers "F.Cu" "F.Mask" "F.Paste")
			(net "P5E_PEX0_STN6_TX_DP<96>")
		)
		(pad "2" smd rect
			(at 0.2667 0 90)
			(size 0.3048 0.381)
			(layers "F.Cu" "F.Mask" "F.Paste")
			(net "P5E_PEX0_STN6_TX_C_DP<96>")
		)
	)
	(footprint ""
		(layer "F.Cu")
		(at 365.072422 -391.66546 90)
		(property "Reference" "R6699"
			(at 0 0 90)
			(layer "F.SilkS")
			(hide yes)
			(effects
				(font
					(size 1.27 1.27)
				)
			)
		)
		(property "Value" ""
			(at 0 0 90)
			(layer "F.Fab")
			(effects
				(font
					(size 1.27 1.27)
				)
			)
		)
		(duplicate_pad_numbers_are_jumpers no)
		(fp_line
			(start 0.7874 -0.4064)
			(end 0.7874 0.4064)
			(stroke
				(width 0.1524)
				(type default)
			)
			(layer "F.SilkS")
		)
		(fp_line
			(start -0.7874 -0.4064)
			(end 0.7874 -0.4064)
			(stroke
				(width 0.1524)
				(type default)
			)
			(layer "F.SilkS")
		)
		(fp_line
			(start 0.7874 0.4064)
			(end -0.7874 0.4064)
			(stroke
				(width 0.1524)
				(type default)
			)
			(layer "F.SilkS")
		)
		(fp_line
			(start -0.7874 0.4064)
			(end -0.7874 -0.4064)
			(stroke
				(width 0.1524)
				(type default)
			)
			(layer "F.SilkS")
		)
		(fp_line
			(start -0.12065 -0.305054)
			(end -0.12065 -0.2794)
			(stroke
				(width 0.1)
				(type default)
			)
			(layer "F.Fab")
		)
		(fp_line
			(start -0.67945 -0.305054)
			(end -0.12065 -0.305054)
			(stroke
				(width 0.1)
				(type default)
			)
			(layer "F.Fab")
		)
		(fp_line
			(start 0.67945 -0.3048)
			(end 0.67945 0.3048)
			(stroke
				(width 0.1)
				(type default)
			)
			(layer "F.Fab")
		)
		(fp_line
			(start 0.12065 -0.3048)
			(end 0.67945 -0.3048)
			(stroke
				(width 0.1)
				(type default)
			)
			(layer "F.Fab")
		)
		(fp_line
			(start 0.12065 -0.2794)
			(end 0.12065 -0.3048)
			(stroke
				(width 0.1)
				(type default)
			)
			(layer "F.Fab")
		)
		(fp_line
			(start -0.12065 -0.2794)
			(end 0.12065 -0.2794)
			(stroke
				(width 0.1)
				(type default)
			)
			(layer "F.Fab")
		)
		(fp_line
			(start 0.120396 0.2794)
			(end -0.12065 0.2794)
			(stroke
				(width 0.1)
				(type default)
			)
			(layer "F.Fab")
		)
		(fp_line
			(start -0.12065 0.2794)
			(end -0.12065 0.3048)
			(stroke
				(width 0.1)
				(type default)
			)
			(layer "F.Fab")
		)
		(fp_line
			(start 0.67945 0.3048)
			(end 0.120396 0.3048)
			(stroke
				(width 0.1)
				(type default)
			)
			(layer "F.Fab")
		)
		(fp_line
			(start 0.120396 0.3048)
			(end 0.120396 0.2794)
			(stroke
				(width 0.1)
				(type default)
			)
			(layer "F.Fab")
		)
		(fp_line
			(start -0.12065 0.3048)
			(end -0.67945 0.3048)
			(stroke
				(width 0.1)
				(type default)
			)
			(layer "F.Fab")
		)
		(fp_line
			(start -0.67945 0.3048)
			(end -0.67945 -0.305054)
			(stroke
				(width 0.1)
				(type default)
			)
			(layer "F.Fab")
		)
		(pad "1" smd circle
			(at -0.40005 0 90)
			(size 0 0)
			(layers "F.Cu" "F.Mask" "F.Paste")
			(net "MB_3V3IO_RSVD1")
		)
		(pad "2" smd circle
			(at 0.40005 0 90)
			(size 0 0)
			(layers "F.Cu" "F.Mask" "F.Paste")
			(net "GND")
		)
	)
	(footprint ""
		(layer "F.Cu")
		(at 434.478938 -59.577986 -90)
		(property "Reference" "R900"
			(at 0 0 270)
			(layer "F.SilkS")
			(hide yes)
			(effects
				(font
					(size 1.27 1.27)
				)
			)
		)
		(property "Value" ""
			(at 0 0 270)
			(layer "F.Fab")
			(effects
				(font
					(size 1.27 1.27)
				)
			)
		)
		(duplicate_pad_numbers_are_jumpers no)
		(fp_line
			(start -0.7874 0.4064)
			(end -0.7874 -0.4064)
			(stroke
				(width 0.1524)
				(type default)
			)
			(layer "F.SilkS")
		)
		(fp_line
			(start 0.7874 0.4064)
			(end -0.7874 0.4064)
			(stroke
				(width 0.1524)
				(type default)
			)
			(layer "F.SilkS")
		)
		(fp_line
			(start -0.7874 -0.4064)
			(end 0.7874 -0.4064)
			(stroke
				(width 0.1524)
				(type default)
			)
			(layer "F.SilkS")
		)
		(fp_line
			(start 0.7874 -0.4064)
			(end 0.7874 0.4064)
			(stroke
				(width 0.1524)
				(type default)
			)
			(layer "F.SilkS")
		)
		(fp_line
			(start -0.67945 0.3048)
			(end -0.67945 -0.305054)
			(stroke
				(width 0.1)
				(type default)
			)
			(layer "F.Fab")
		)
		(fp_line
			(start -0.12065 0.3048)
			(end -0.67945 0.3048)
			(stroke
				(width 0.1)
				(type default)
			)
			(layer "F.Fab")
		)
		(fp_line
			(start 0.120396 0.3048)
			(end 0.120396 0.2794)
			(stroke
				(width 0.1)
				(type default)
			)
			(layer "F.Fab")
		)
		(fp_line
			(start 0.67945 0.3048)
			(end 0.120396 0.3048)
			(stroke
				(width 0.1)
				(type default)
			)
			(layer "F.Fab")
		)
		(fp_line
			(start -0.12065 0.2794)
			(end -0.12065 0.3048)
			(stroke
				(width 0.1)
				(type default)
			)
			(layer "F.Fab")
		)
		(fp_line
			(start 0.120396 0.2794)
			(end -0.12065 0.2794)
			(stroke
				(width 0.1)
				(type default)
			)
			(layer "F.Fab")
		)
		(fp_line
			(start -0.12065 -0.2794)
			(end 0.12065 -0.2794)
			(stroke
				(width 0.1)
				(type default)
			)
			(layer "F.Fab")
		)
		(fp_line
			(start 0.12065 -0.2794)
			(end 0.12065 -0.3048)
			(stroke
				(width 0.1)
				(type default)
			)
			(layer "F.Fab")
		)
		(fp_line
			(start 0.12065 -0.3048)
			(end 0.67945 -0.3048)
			(stroke
				(width 0.1)
				(type default)
			)
			(layer "F.Fab")
		)
		(fp_line
			(start 0.67945 -0.3048)
			(end 0.67945 0.3048)
			(stroke
				(width 0.1)
				(type default)
			)
			(layer "F.Fab")
		)
		(fp_line
			(start -0.67945 -0.305054)
			(end -0.12065 -0.305054)
			(stroke
				(width 0.1)
				(type default)
			)
			(layer "F.Fab")
		)
		(fp_line
			(start -0.12065 -0.305054)
			(end -0.12065 -0.2794)
			(stroke
				(width 0.1)
				(type default)
			)
			(layer "F.Fab")
		)
		(pad "1" smd circle
			(at -0.40005 0 270)
			(size 0 0)
			(layers "F.Cu" "F.Mask" "F.Paste")
			(net "P3V3_SSD15")
		)
		(pad "2" smd circle
			(at 0.40005 0 270)
			(size 0 0)
			(layers "F.Cu" "F.Mask" "F.Paste")
			(net "PWRGD_P3V3_SSD15")
		)
	)
	(footprint ""
		(layer "F.Cu")
		(at 64.455802 -356.244906 90)
		(property "Reference" "C123"
			(at 0 0 90)
			(layer "F.SilkS")
			(hide yes)
			(effects
				(font
					(size 1.27 1.27)
				)
			)
		)
		(property "Value" ""
			(at 0 0 90)
			(layer "F.Fab")
			(effects
				(font
					(size 1.27 1.27)
				)
			)
		)
		(duplicate_pad_numbers_are_jumpers no)
		(fp_line
			(start 0.299974 -0.150114)
			(end 0.299974 0.150114)
			(stroke
				(width 0.1)
				(type default)
			)
			(layer "F.Fab")
		)
		(fp_line
			(start -0.299974 -0.150114)
			(end 0.299974 -0.150114)
			(stroke
				(width 0.1)
				(type default)
			)
			(layer "F.Fab")
		)
		(fp_line
			(start 0.299974 0.150114)
			(end -0.299974 0.150114)
			(stroke
				(width 0.1)
				(type default)
			)
			(layer "F.Fab")
		)
		(fp_line
			(start -0.299974 0.150114)
			(end -0.299974 -0.150114)
			(stroke
				(width 0.1)
				(type default)
			)
			(layer "F.Fab")
		)
		(pad "1" smd rect
			(at -0.2667 0 90)
			(size 0.3048 0.381)
			(layers "F.Cu" "F.Mask" "F.Paste")
			(net "P5E_PEX0_STN5_TX_DP<82>")
		)
		(pad "2" smd rect
			(at 0.2667 0 90)
			(size 0.3048 0.381)
			(layers "F.Cu" "F.Mask" "F.Paste")
			(net "P5E_PEX0_STN5_TX_C_DP<82>")
		)
	)
	(footprint ""
		(layer "F.Cu")
		(at 204.115416 -306.06365 90)
		(property "Reference" "R3929"
			(at 0 0 90)
			(layer "F.SilkS")
			(hide yes)
			(effects
				(font
					(size 1.27 1.27)
				)
			)
		)
		(property "Value" ""
			(at 0 0 90)
			(layer "F.Fab")
			(effects
				(font
					(size 1.27 1.27)
				)
			)
		)
		(duplicate_pad_numbers_are_jumpers no)
		(fp_line
			(start 0.7874 -0.4064)
			(end 0.7874 0.4064)
			(stroke
				(width 0.1524)
				(type default)
			)
			(layer "F.SilkS")
		)
		(fp_line
			(start -0.7874 -0.4064)
			(end 0.7874 -0.4064)
			(stroke
				(width 0.1524)
				(type default)
			)
			(layer "F.SilkS")
		)
		(fp_line
			(start 0.7874 0.4064)
			(end -0.7874 0.4064)
			(stroke
				(width 0.1524)
				(type default)
			)
			(layer "F.SilkS")
		)
		(fp_line
			(start -0.7874 0.4064)
			(end -0.7874 -0.4064)
			(stroke
				(width 0.1524)
				(type default)
			)
			(layer "F.SilkS")
		)
		(fp_line
			(start -0.12065 -0.305054)
			(end -0.12065 -0.2794)
			(stroke
				(width 0.1)
				(type default)
			)
			(layer "F.Fab")
		)
		(fp_line
			(start -0.67945 -0.305054)
			(end -0.12065 -0.305054)
			(stroke
				(width 0.1)
				(type default)
			)
			(layer "F.Fab")
		)
		(fp_line
			(start 0.67945 -0.3048)
			(end 0.67945 0.3048)
			(stroke
				(width 0.1)
				(type default)
			)
			(layer "F.Fab")
		)
		(fp_line
			(start 0.12065 -0.3048)
			(end 0.67945 -0.3048)
			(stroke
				(width 0.1)
				(type default)
			)
			(layer "F.Fab")
		)
		(fp_line
			(start 0.12065 -0.2794)
			(end 0.12065 -0.3048)
			(stroke
				(width 0.1)
				(type default)
			)
			(layer "F.Fab")
		)
		(fp_line
			(start -0.12065 -0.2794)
			(end 0.12065 -0.2794)
			(stroke
				(width 0.1)
				(type default)
			)
			(layer "F.Fab")
		)
		(fp_line
			(start 0.120396 0.2794)
			(end -0.12065 0.2794)
			(stroke
				(width 0.1)
				(type default)
			)
			(layer "F.Fab")
		)
		(fp_line
			(start -0.12065 0.2794)
			(end -0.12065 0.3048)
			(stroke
				(width 0.1)
				(type default)
			)
			(layer "F.Fab")
		)
		(fp_line
			(start 0.67945 0.3048)
			(end 0.120396 0.3048)
			(stroke
				(width 0.1)
				(type default)
			)
			(layer "F.Fab")
		)
		(fp_line
			(start 0.120396 0.3048)
			(end 0.120396 0.2794)
			(stroke
				(width 0.1)
				(type default)
			)
			(layer "F.Fab")
		)
		(fp_line
			(start -0.12065 0.3048)
			(end -0.67945 0.3048)
			(stroke
				(width 0.1)
				(type default)
			)
			(layer "F.Fab")
		)
		(fp_line
			(start -0.67945 0.3048)
			(end -0.67945 -0.305054)
			(stroke
				(width 0.1)
				(type default)
			)
			(layer "F.Fab")
		)
		(pad "1" smd circle
			(at -0.40005 0 90)
			(size 0 0)
			(layers "F.Cu" "F.Mask" "F.Paste")
			(net "SMB_PEX1_SLAVE_SDA")
		)
		(pad "2" smd circle
			(at 0.40005 0 90)
			(size 0 0)
			(layers "F.Cu" "F.Mask" "F.Paste")
			(net "SMB_PEX1_R_SDA")
		)
	)
)
